# S9S_MB_2U (Grand Teton) — schematic netlist excerpt (pin names and nets, part order shuffled) for the footprints in the layout excerpt that follows; sources: Cadence DE-HDL packaged netlist, KiCad conversion of 03242023_DA0F0TMBIJ0_F0T_Motherboard_J_brd_V01_OCP.brd

R4716  Q_RES  8.45K 1% EMPTY  pkg 0402LF  page 224 : A = P3V3_AUX ; B = FM_AC_PWR_BTN_R_N
C1007  Q_CAP  22UF 4V 20% X6S  pkg C0402  page 74 : A = PVCCIN_CPU0 ; B = GND

(kicad_pcb
	(version 20260206)
	(generator "pcbnew")
	(generator_version "10.0")
	(general
		(thickness 1.6)
		(legacy_teardrops no)
	)
	(paper "A4")
	(title_block
		(title "03242023_DA0F0TMBIJ0_F0T_Motherboard_J_brd_V01_OCP.brd")
		(comment 1 "Grand Teton / footprints 1716-1717 of 6105")
	)
	(layers
		(0 "F.Cu" signal "TOP")
		(4 "In1.Cu" signal "GND")
		(6 "In2.Cu" signal "IN1")
		(8 "In3.Cu" signal "GND1")
		(10 "In4.Cu" signal "IN2")
		(12 "In5.Cu" signal "GND2")
		(14 "In6.Cu" signal "IN3")
		(16 "In7.Cu" signal "GND3")
		(18 "In8.Cu" signal "VCC")
		(20 "In9.Cu" signal "VCC1")
		(22 "In10.Cu" signal "GND4")
		(24 "In11.Cu" signal "IN4")
		(26 "In12.Cu" signal "GND5")
		(28 "In13.Cu" signal "IN5")
		(30 "In14.Cu" signal "GND6")
		(32 "In15.Cu" signal "IN6")
		(34 "In16.Cu" signal "GND7")
		(2 "B.Cu" signal "BOTTOM")
		(9 "F.Adhes" user "F.Adhesive")
		(11 "B.Adhes" user "B.Adhesive")
		(13 "F.Paste" user "Package Geometry/Pastemask Top")
		(15 "B.Paste" user "Package Geometry/Pastemask Bottom")
		(5 "F.SilkS" user "Ref Des/Silkscreen Top")
		(7 "B.SilkS" user "Ref Des/Silkscreen Bottom")
		(1 "F.Mask" user "Board Geometry/Soldermask Top")
		(3 "B.Mask" user "Board Geometry/Soldermask Bottom")
		(17 "Dwgs.User" user "User.Drawings")
		(19 "Cmts.User" user "User.Comments")
		(21 "Eco1.User" user "User.Eco1")
		(23 "Eco2.User" user "User.Eco2")
		(25 "Edge.Cuts" user "Board Geometry/Outline")
		(27 "Margin" user)
		(31 "F.CrtYd" user "Package Geometry/Place Bound Top")
		(29 "B.CrtYd" user "Package Geometry/Place Bound Bottom")
		(35 "F.Fab" user "Ref Des/Assembly Top")
		(33 "B.Fab" user "Ref Des/Assembly Bottom")
	)
	(footprint ""
		(layer "F.Cu")
		(at 355.236018 -244.03177 90)
		(property "Reference" "C1007"
			(at 0 0 90)
			(layer "F.SilkS")
			(hide yes)
			(effects
				(font
					(size 1.27 1.27)
				)
			)
		)
		(property "Value" ""
			(at 0 0 90)
			(layer "F.Fab")
			(effects
				(font
					(size 1.27 1.27)
				)
			)
		)
		(duplicate_pad_numbers_are_jumpers no)
		(fp_line
			(start 0.7874 -0.4064)
			(end 0.7874 0.4064)
			(stroke
				(width 0.1524)
				(type default)
			)
			(layer "F.SilkS")
		)
		(fp_line
			(start -0.7874 -0.4064)
			(end 0.7874 -0.4064)
			(stroke
				(width 0.1524)
				(type default)
			)
			(layer "F.SilkS")
		)
		(fp_line
			(start 0.7874 0.4064)
			(end -0.7874 0.4064)
			(stroke
				(width 0.1524)
				(type default)
			)
			(layer "F.SilkS")
		)
		(fp_line
			(start -0.7874 0.4064)
			(end -0.7874 -0.4064)
			(stroke
				(width 0.1524)
				(type default)
			)
			(layer "F.SilkS")
		)
		(fp_line
			(start -0.12065 -0.305054)
			(end -0.12065 -0.2794)
			(stroke
				(width 0.1)
				(type default)
			)
			(layer "F.Fab")
		)
		(fp_line
			(start -0.67945 -0.305054)
			(end -0.12065 -0.305054)
			(stroke
				(width 0.1)
				(type default)
			)
			(layer "F.Fab")
		)
		(fp_line
			(start 0.67945 -0.3048)
			(end 0.67945 0.3048)
			(stroke
				(width 0.1)
				(type default)
			)
			(layer "F.Fab")
		)
		(fp_line
			(start 0.12065 -0.3048)
			(end 0.67945 -0.3048)
			(stroke
				(width 0.1)
				(type default)
			)
			(layer "F.Fab")
		)
		(fp_line
			(start 0.12065 -0.2794)
			(end 0.12065 -0.3048)
			(stroke
				(width 0.1)
				(type default)
			)
			(layer "F.Fab")
		)
		(fp_line
			(start -0.12065 -0.2794)
			(end 0.12065 -0.2794)
			(stroke
				(width 0.1)
				(type default)
			)
			(layer "F.Fab")
		)
		(fp_line
			(start 0.120396 0.2794)
			(end -0.12065 0.2794)
			(stroke
				(width 0.1)
				(type default)
			)
			(layer "F.Fab")
		)
		(fp_line
			(start -0.12065 0.2794)
			(end -0.12065 0.3048)
			(stroke
				(width 0.1)
				(type default)
			)
			(layer "F.Fab")
		)
		(fp_line
			(start 0.67945 0.3048)
			(end 0.120396 0.3048)
			(stroke
				(width 0.1)
				(type default)
			)
			(layer "F.Fab")
		)
		(fp_line
			(start 0.120396 0.3048)
			(end 0.120396 0.2794)
			(stroke
				(width 0.1)
				(type default)
			)
			(layer "F.Fab")
		)
		(fp_line
			(start -0.12065 0.3048)
			(end -0.67945 0.3048)
			(stroke
				(width 0.1)
				(type default)
			)
			(layer "F.Fab")
		)
		(fp_line
			(start -0.67945 0.3048)
			(end -0.67945 -0.305054)
			(stroke
				(width 0.1)
				(type default)
			)
			(layer "F.Fab")
		)
		(pad "1" smd circle
			(at -0.40005 0 90)
			(size 0 0)
			(layers "F.Cu" "F.Mask" "F.Paste")
			(net "PVCCIN_CPU0")
		)
		(pad "2" smd circle
			(at 0.40005 0 90)
			(size 0 0)
			(layers "F.Cu" "F.Mask" "F.Paste")
			(net "GND")
		)
	)
	(footprint ""
		(layer "F.Cu")
		(at 216.1286 -121.1326)
		(property "Reference" "R4716"
			(at 0 0 0)
			(layer "F.SilkS")
			(hide yes)
			(effects
				(font
					(size 1.27 1.27)
				)
			)
		)
		(property "Value" ""
			(at 0 0 0)
			(layer "F.Fab")
			(effects
				(font
					(size 1.27 1.27)
				)
			)
		)
		(duplicate_pad_numbers_are_jumpers no)
		(fp_line
			(start -0.7874 -0.4064)
			(end 0.7874 -0.4064)
			(stroke
				(width 0.1524)
				(type default)
			)
			(layer "F.SilkS")
		)
		(fp_line
			(start -0.7874 0.4064)
			(end -0.7874 -0.4064)
			(stroke
				(width 0.1524)
				(type default)
			)
			(layer "F.SilkS")
		)
		(fp_line
			(start 0.7874 -0.4064)
			(end 0.7874 0.4064)
			(stroke
				(width 0.1524)
				(type default)
			)
			(layer "F.SilkS")
		)
		(fp_line
			(start 0.7874 0.4064)
			(end -0.7874 0.4064)
			(stroke
				(width 0.1524)
				(type default)
			)
			(layer "F.SilkS")
		)
		(fp_line
			(start -0.67945 -0.305054)
			(end -0.12065 -0.305054)
			(stroke
				(width 0.1)
				(type default)
			)
			(layer "F.Fab")
		)
		(fp_line
			(start -0.67945 0.3048)
			(end -0.67945 -0.305054)
			(stroke
				(width 0.1)
				(type default)
			)
			(layer "F.Fab")
		)
		(fp_line
			(start -0.12065 -0.305054)
			(end -0.12065 -0.2794)
			(stroke
				(width 0.1)
				(type default)
			)
			(layer "F.Fab")
		)
		(fp_line
			(start -0.12065 -0.2794)
			(end 0.12065 -0.2794)
			(stroke
				(width 0.1)
				(type default)
			)
			(layer "F.Fab")
		)
		(fp_line
			(start -0.12065 0.2794)
			(end -0.12065 0.3048)
			(stroke
				(width 0.1)
				(type default)
			)
			(layer "F.Fab")
		)
		(fp_line
			(start -0.12065 0.3048)
			(end -0.67945 0.3048)
			(stroke
				(width 0.1)
				(type default)
			)
			(layer "F.Fab")
		)
		(fp_line
			(start 0.120396 0.2794)
			(end -0.12065 0.2794)
			(stroke
				(width 0.1)
				(type default)
			)
			(layer "F.Fab")
		)
		(fp_line
			(start 0.120396 0.3048)
			(end 0.120396 0.2794)
			(stroke
				(width 0.1)
				(type default)
			)
			(layer "F.Fab")
		)
		(fp_line
			(start 0.12065 -0.3048)
			(end 0.67945 -0.3048)
			(stroke
				(width 0.1)
				(type default)
			)
			(layer "F.Fab")
		)
		(fp_line
			(start 0.12065 -0.2794)
			(end 0.12065 -0.3048)
			(stroke
				(width 0.1)
				(type default)
			)
			(layer "F.Fab")
		)
		(fp_line
			(start 0.67945 -0.3048)
			(end 0.67945 0.3048)
			(stroke
				(width 0.1)
				(type default)
			)
			(layer "F.Fab")
		)
		(fp_line
			(start 0.67945 0.3048)
			(end 0.120396 0.3048)
			(stroke
				(width 0.1)
				(type default)
			)
			(layer "F.Fab")
		)
		(pad "1" smd circle
			(at -0.40005 0)
			(size 0 0)
			(layers "F.Cu" "F.Mask" "F.Paste")
			(net "P3V3_AUX")
		)
		(pad "2" smd circle
			(at 0.40005 0)
			(size 0 0)
			(layers "F.Cu" "F.Mask" "F.Paste")
			(net "FM_AC_PWR_BTN_R_N")
		)
	)
)
